(kicad_pcb
	(version 20211014)
	(generator pcbnew)
	(general
    (thickness 1.6)
  )
	(paper "A4")
	(title_block
    (title "SA800U (Snapdragon 845) Baseboard")
    (date "2023-10-19")
    (rev "1.0.3")
    (company "Antmicro Ltd.")
    (comment 1 "www.antmicro.com")
		(comment 9 "footprints 392-401 of 589")
	)
	(layers
    (0 "F.Cu" signal)
    (1 "In1.Cu" power)
    (2 "In2.Cu" signal)
    (3 "In3.Cu" signal)
    (4 "In4.Cu" power)
    (31 "B.Cu" signal)
    (32 "B.Adhes" user "B.Adhesive")
    (33 "F.Adhes" user "F.Adhesive")
    (34 "B.Paste" user)
    (35 "F.Paste" user)
    (36 "B.SilkS" user "B.Silkscreen")
    (37 "F.SilkS" user "F.Silkscreen")
    (38 "B.Mask" user)
    (39 "F.Mask" user)
    (40 "Dwgs.User" user "User.Drawings")
    (41 "Cmts.User" user "User.Comments")
    (42 "Eco1.User" user "User.Eco1")
    (43 "Eco2.User" user "User.Eco2")
    (44 "Edge.Cuts" user)
    (45 "Margin" user)
    (46 "B.CrtYd" user "B.Courtyard")
    (47 "F.CrtYd" user "F.Courtyard")
    (48 "B.Fab" user)
    (49 "F.Fab" user)
  )
	(footprint "sa800u-baseboard-hw-footprints:R_0402_1005Metric" (layer "B.Cu")
    (tedit 5FD9C158)
    (at 111 146.4)
    (descr "Resistor SMD 0402")
    (tags "resistor SMD 0402")
    (property "Author" "Antmicro")
    (property "License" "Apache-2.0")
    (property "MPN" "ERA2AED104X")
    (property "Manufacturer" "Panasonic")
    (property "Sheetfile" "usb-c-interface.kicad_sch")
    (property "Sheetname" "USB-C Interface ")
    (property "Val" "100k_0.5%")
    (attr smd)
    (fp_text reference "R59" (at 3.07 0.39 180) (layer "B.SilkS")
      (effects (font (size 0.7 0.7) (thickness 0.15)) (justify left bottom mirror))
    )
    (fp_text value "R_100k_0.5%_0402" (at 0 -1.4 180) (layer "B.Fab")
      (effects (font (size 0.7 0.7) (thickness 0.15)) (justify left bottom mirror))
    )
    (fp_text user "${REFERENCE}" (at -0.95 -3.168 180) (layer "B.Fab") hide
      (effects (font (size 0.7 0.7) (thickness 0.15)) (justify left bottom mirror))
    )
    (fp_text user "Author: Antmicro" (at -0.95 -4.169 180) (layer "B.Fab") hide
      (effects (font (size 0.7 0.7) (thickness 0.15)) (justify left bottom mirror))
    )
    (fp_text user "License: Apache-2.0" (at -0.95 -5.169 180) (layer "B.Fab") hide
      (effects (font (size 0.7 0.7) (thickness 0.15)) (justify left bottom mirror))
    )
    (fp_rect (start -0.93 0.47) (end 0.93 -0.47) (layer "B.CrtYd") (width 0.05) (fill none))
    (fp_rect (start -0.5 0.25) (end 0.5 -0.25) (layer "B.Fab") (width 0.15) (fill none))
    (pad "1" smd roundrect (at -0.485 0) (size 0.59 0.64) (layers "B.Cu" "B.Paste" "B.Mask") (roundrect_rratio 0.25)
      (net 396 "Net-(R59-Pad1)") (pintype "passive"))
    (pad "2" smd roundrect (at 0.485 0) (size 0.59 0.64) (layers "B.Cu" "B.Paste" "B.Mask") (roundrect_rratio 0.25)
      (net 1 "GND") (pintype "passive"))
  )
	(footprint "sa800u-baseboard-hw-footprints:R_0402_1005Metric" (layer "B.Cu")
    (tedit 5FD9C158)
    (at 112 140.9 90)
    (descr "Resistor SMD 0402")
    (tags "resistor SMD 0402")
    (property "Author" "Antmicro")
    (property "License" "Apache-2.0")
    (property "MPN" "CR0402-FX-1003GLF")
    (property "Manufacturer" "Bourns")
    (property "Sheetfile" "usb-c-interface.kicad_sch")
    (property "Sheetname" "USB-C Interface ")
    (property "Tolerance" "1%")
    (property "Val" "100k")
    (attr smd)
    (fp_text reference "R60" (at 1.06 3.34 270) (layer "B.SilkS")
      (effects (font (size 0.7 0.7) (thickness 0.15)) (justify left bottom mirror))
    )
    (fp_text value "R_100k_0402" (at 0 -1.4 270) (layer "B.Fab")
      (effects (font (size 0.7 0.7) (thickness 0.15)) (justify left bottom mirror))
    )
    (fp_text user "License: Apache-2.0" (at -0.95 -5.169 270) (layer "B.Fab") hide
      (effects (font (size 0.7 0.7) (thickness 0.15)) (justify left bottom mirror))
    )
    (fp_text user "${REFERENCE}" (at -0.95 -3.168 270) (layer "B.Fab") hide
      (effects (font (size 0.7 0.7) (thickness 0.15)) (justify left bottom mirror))
    )
    (fp_text user "Author: Antmicro" (at -0.95 -4.169 270) (layer "B.Fab") hide
      (effects (font (size 0.7 0.7) (thickness 0.15)) (justify left bottom mirror))
    )
    (fp_rect (start -0.93 0.47) (end 0.93 -0.47) (layer "B.CrtYd") (width 0.05) (fill none))
    (fp_rect (start -0.5 0.25) (end 0.5 -0.25) (layer "B.Fab") (width 0.15) (fill none))
    (pad "1" smd roundrect (at -0.485 0 90) (size 0.59 0.64) (layers "B.Cu" "B.Paste" "B.Mask") (roundrect_rratio 0.25)
      (net 290 "/USB-C Interface /USB2_CC_SELECT") (pintype "passive"))
    (pad "2" smd roundrect (at 0.485 0 90) (size 0.59 0.64) (layers "B.Cu" "B.Paste" "B.Mask") (roundrect_rratio 0.25)
      (net 133 "5V_SYS") (pintype "passive"))
  )
	(footprint "sa800u-baseboard-hw-footprints:C_0603_1608Metric" (layer "B.Cu")
    (tedit 5D5E94D2)
    (at 106.9 142.85 -90)
    (descr "Capacitor SMD 0603")
    (tags "capacitor 0603")
    (property "Author" "Antmicro")
    (property "Dielectric" "")
    (property "License" "Apache-2.0")
    (property "MPN" "GRM188R60J476ME15D")
    (property "Manufacturer" "Murata")
    (property "Sheetfile" "usb-c-interface.kicad_sch")
    (property "Sheetname" "USB-C Interface ")
    (property "Val" "47u")
    (property "Voltage" "")
    (attr smd)
    (fp_text reference "C58" (at -1.63 0.54 90) (layer "B.SilkS")
      (effects (font (size 0.7 0.7) (thickness 0.15)) (justify left bottom mirror))
    )
    (fp_text value "C_47u_0603" (at 0 -1.6 90) (layer "B.Fab")
      (effects (font (size 0.7 0.7) (thickness 0.15)) (justify left bottom mirror))
    )
    (fp_text user "License: Apache-2.0" (at -1.682 -5.895 90) (layer "B.Fab") hide
      (effects (font (size 0.7 0.7) (thickness 0.15)) (justify left bottom mirror))
    )
    (fp_text user "Author: Antmicro" (at -1.682 -4.894 90) (layer "B.Fab") hide
      (effects (font (size 0.7 0.7) (thickness 0.15)) (justify left bottom mirror))
    )
    (fp_text user "${REFERENCE}" (at -1.682 -3.895 90) (layer "B.Fab") hide
      (effects (font (size 0.7 0.7) (thickness 0.15)) (justify left bottom mirror))
    )
    (fp_line (start -0.3 -0.3) (end 0.3 -0.3) (layer "B.SilkS") (width 0.15))
    (fp_line (start -0.3 0.3) (end 0.3 0.3) (layer "B.SilkS") (width 0.15))
    (fp_rect (start -1.24 0.7) (end 1.24 -0.7) (layer "B.CrtYd") (width 0.05) (fill none))
    (fp_rect (start -0.8 0.4) (end 0.8 -0.4) (layer "B.Fab") (width 0.15) (fill none))
    (pad "1" smd roundrect (at -0.7 0 270) (size 0.6 0.8) (layers "B.Cu" "B.Paste" "B.Mask") (roundrect_rratio 0.2)
      (net 133 "5V_SYS") (pintype "passive"))
    (pad "2" smd roundrect (at 0.7 0 270) (size 0.6 0.8) (layers "B.Cu" "B.Paste" "B.Mask") (roundrect_rratio 0.2)
      (net 1 "GND") (pintype "passive"))
  )
	(footprint "sa800u-baseboard-hw-footprints:C_0603_1608Metric" (layer "B.Cu")
    (tedit 5D5E94D2)
    (at 107.25 139.6 90)
    (descr "Capacitor SMD 0603")
    (tags "capacitor 0603")
    (property "Author" "Antmicro")
    (property "Dielectric" "")
    (property "License" "Apache-2.0")
    (property "MPN" "GRM188R60J476ME15D")
    (property "Manufacturer" "Murata")
    (property "Sheetfile" "usb-c-interface.kicad_sch")
    (property "Sheetname" "USB-C Interface ")
    (property "Val" "47u")
    (property "Voltage" "")
    (attr smd)
    (fp_text reference "C59" (at 3.13 0.38 270) (layer "B.SilkS")
      (effects (font (size 0.7 0.7) (thickness 0.15)) (justify left bottom mirror))
    )
    (fp_text value "C_47u_0603" (at 0 -1.6 270) (layer "B.Fab")
      (effects (font (size 0.7 0.7) (thickness 0.15)) (justify left bottom mirror))
    )
    (fp_text user "License: Apache-2.0" (at -1.682 -5.895 270) (layer "B.Fab") hide
      (effects (font (size 0.7 0.7) (thickness 0.15)) (justify left bottom mirror))
    )
    (fp_text user "Author: Antmicro" (at -1.682 -4.894 270) (layer "B.Fab") hide
      (effects (font (size 0.7 0.7) (thickness 0.15)) (justify left bottom mirror))
    )
    (fp_text user "${REFERENCE}" (at -1.682 -3.895 270) (layer "B.Fab") hide
      (effects (font (size 0.7 0.7) (thickness 0.15)) (justify left bottom mirror))
    )
    (fp_line (start -0.3 -0.3) (end 0.3 -0.3) (layer "B.SilkS") (width 0.15))
    (fp_line (start -0.3 0.3) (end 0.3 0.3) (layer "B.SilkS") (width 0.15))
    (fp_rect (start -1.24 0.7) (end 1.24 -0.7) (layer "B.CrtYd") (width 0.05) (fill none))
    (fp_rect (start -0.8 0.4) (end 0.8 -0.4) (layer "B.Fab") (width 0.15) (fill none))
    (pad "1" smd roundrect (at -0.7 0 90) (size 0.6 0.8) (layers "B.Cu" "B.Paste" "B.Mask") (roundrect_rratio 0.2)
      (net 133 "5V_SYS") (pintype "passive"))
    (pad "2" smd roundrect (at 0.7 0 90) (size 0.6 0.8) (layers "B.Cu" "B.Paste" "B.Mask") (roundrect_rratio 0.2)
      (net 1 "GND") (pintype "passive"))
  )
	(footprint "sa800u-baseboard-hw-footprints:C_0603_1608Metric" (layer "B.Cu")
    (tedit 5D5E94D2)
    (at 108.75 139.6 90)
    (descr "Capacitor SMD 0603")
    (tags "capacitor 0603")
    (property "Author" "Antmicro")
    (property "Dielectric" "")
    (property "License" "Apache-2.0")
    (property "MPN" "GRM188R60J476ME15D")
    (property "Manufacturer" "Murata")
    (property "Sheetfile" "usb-c-interface.kicad_sch")
    (property "Sheetname" "USB-C Interface ")
    (property "Val" "47u")
    (property "Voltage" "")
    (attr smd)
    (fp_text reference "C62" (at 3.13 0.38 270) (layer "B.SilkS")
      (effects (font (size 0.7 0.7) (thickness 0.15)) (justify left bottom mirror))
    )
    (fp_text value "C_47u_0603" (at 0 -1.6 270) (layer "B.Fab")
      (effects (font (size 0.7 0.7) (thickness 0.15)) (justify left bottom mirror))
    )
    (fp_text user "${REFERENCE}" (at -1.682 -3.895 270) (layer "B.Fab") hide
      (effects (font (size 0.7 0.7) (thickness 0.15)) (justify left bottom mirror))
    )
    (fp_text user "License: Apache-2.0" (at -1.682 -5.895 270) (layer "B.Fab") hide
      (effects (font (size 0.7 0.7) (thickness 0.15)) (justify left bottom mirror))
    )
    (fp_text user "Author: Antmicro" (at -1.682 -4.894 270) (layer "B.Fab") hide
      (effects (font (size 0.7 0.7) (thickness 0.15)) (justify left bottom mirror))
    )
    (fp_line (start -0.3 -0.3) (end 0.3 -0.3) (layer "B.SilkS") (width 0.15))
    (fp_line (start -0.3 0.3) (end 0.3 0.3) (layer "B.SilkS") (width 0.15))
    (fp_rect (start -1.24 0.7) (end 1.24 -0.7) (layer "B.CrtYd") (width 0.05) (fill none))
    (fp_rect (start -0.8 0.4) (end 0.8 -0.4) (layer "B.Fab") (width 0.15) (fill none))
    (pad "1" smd roundrect (at -0.7 0 90) (size 0.6 0.8) (layers "B.Cu" "B.Paste" "B.Mask") (roundrect_rratio 0.2)
      (net 133 "5V_SYS") (pintype "passive"))
    (pad "2" smd roundrect (at 0.7 0 90) (size 0.6 0.8) (layers "B.Cu" "B.Paste" "B.Mask") (roundrect_rratio 0.2)
      (net 1 "GND") (pintype "passive"))
  )
	(footprint "sa800u-baseboard-hw-footprints:C_0402_1005Metric" (layer "B.Cu")
    (tedit 616D63CF)
    (at 107.5 147.25 -90)
    (descr "Capacitor SMD 0402")
    (tags "capacitor SMD 0402")
    (property "Author" "Antmicro")
    (property "Dielectric" "")
    (property "License" "Apache-2.0")
    (property "MPN" "CC0402MRX5R5BB106")
    (property "Manufacturer" "Yaego")
    (property "Sheetfile" "usb-c-interface.kicad_sch")
    (property "Sheetname" "USB-C Interface ")
    (property "Val" "10u")
    (property "Voltage" "")
    (attr smd)
    (fp_text reference "C71" (at -1.13 0.64 90) (layer "B.SilkS")
      (effects (font (size 0.7 0.7) (thickness 0.15)) (justify left bottom mirror))
    )
    (fp_text value "C_10u_0402" (at 0 -1.4 90) (layer "B.Fab")
      (effects (font (size 0.7 0.7) (thickness 0.15)) (justify left bottom mirror))
    )
    (fp_text user "License: Apache-2.0" (at -0.932 -5.17 90) (layer "B.Fab") hide
      (effects (font (size 0.7 0.7) (thickness 0.15)) (justify left bottom mirror))
    )
    (fp_text user "Author: Antmicro" (at -0.932 -4.17 90) (layer "B.Fab") hide
      (effects (font (size 0.7 0.7) (thickness 0.15)) (justify left bottom mirror))
    )
    (fp_text user "${REFERENCE}" (at -0.932 -3.168 90) (layer "B.Fab") hide
      (effects (font (size 0.7 0.7) (thickness 0.15)) (justify left bottom mirror))
    )
    (fp_rect (start -0.94 0.47) (end 0.94 -0.47) (layer "B.CrtYd") (width 0.05) (fill none))
    (fp_rect (start -0.499 0.249) (end 0.499 -0.249) (layer "B.Fab") (width 0.15) (fill none))
    (pad "1" smd roundrect (at -0.484 0 270) (size 0.59 0.64) (layers "B.Cu" "B.Paste" "B.Mask") (roundrect_rratio 0.25)
      (net 210 "/USB-C Interface /USB2_5V") (pintype "passive"))
    (pad "2" smd roundrect (at 0.484 0 270) (size 0.59 0.64) (layers "B.Cu" "B.Paste" "B.Mask") (roundrect_rratio 0.25)
      (net 1 "GND") (pintype "passive"))
  )
	(footprint "sa800u-baseboard-hw-footprints:R_0402_1005Metric" (layer "B.Cu")
    (tedit 5FD9C158)
    (at 111 140.9 90)
    (descr "Resistor SMD 0402")
    (tags "resistor SMD 0402")
    (property "Author" "Antmicro")
    (property "License" "Apache-2.0")
    (property "MPN" "CR0402-FX-1003GLF")
    (property "Manufacturer" "Bourns")
    (property "Sheetfile" "usb-c-interface.kicad_sch")
    (property "Sheetname" "USB-C Interface ")
    (property "Tolerance" "1%")
    (property "Val" "100k")
    (attr smd)
    (fp_text reference "R61" (at 1.06 3.34 270) (layer "B.SilkS")
      (effects (font (size 0.7 0.7) (thickness 0.15)) (justify left bottom mirror))
    )
    (fp_text value "R_100k_0402" (at 0 -1.4 270) (layer "B.Fab")
      (effects (font (size 0.7 0.7) (thickness 0.15)) (justify left bottom mirror))
    )
    (fp_text user "Author: Antmicro" (at -0.95 -4.169 270) (layer "B.Fab") hide
      (effects (font (size 0.7 0.7) (thickness 0.15)) (justify left bottom mirror))
    )
    (fp_text user "License: Apache-2.0" (at -0.95 -5.169 270) (layer "B.Fab") hide
      (effects (font (size 0.7 0.7) (thickness 0.15)) (justify left bottom mirror))
    )
    (fp_text user "${REFERENCE}" (at -0.95 -3.168 270) (layer "B.Fab") hide
      (effects (font (size 0.7 0.7) (thickness 0.15)) (justify left bottom mirror))
    )
    (fp_rect (start -0.93 0.47) (end 0.93 -0.47) (layer "B.CrtYd") (width 0.05) (fill none))
    (fp_rect (start -0.5 0.25) (end 0.5 -0.25) (layer "B.Fab") (width 0.15) (fill none))
    (pad "1" smd roundrect (at -0.485 0 90) (size 0.59 0.64) (layers "B.Cu" "B.Paste" "B.Mask") (roundrect_rratio 0.25)
      (net 291 "/USB-C Interface /USB2_SINK_5V") (pintype "passive"))
    (pad "2" smd roundrect (at 0.485 0 90) (size 0.59 0.64) (layers "B.Cu" "B.Paste" "B.Mask") (roundrect_rratio 0.25)
      (net 133 "5V_SYS") (pintype "passive"))
  )
	(footprint "sa800u-baseboard-hw-footprints:C_0402_1005Metric" (layer "B.Cu")
    (tedit 616D63CF)
    (at 99.5 138.1 -90)
    (descr "Capacitor SMD 0402")
    (tags "capacitor SMD 0402")
    (property "Author" "Antmicro")
    (property "Dielectric" "X5R")
    (property "License" "Apache-2.0")
    (property "MPN" "GRM155R61H104KE14D")
    (property "Manufacturer" "Murata")
    (property "Sheetfile" "usb-c-interface.kicad_sch")
    (property "Sheetname" "USB-C Interface ")
    (property "Val" "100n")
    (property "Voltage" "50V")
    (attr smd)
    (fp_text reference "C83" (at -3.1 -0.36 90) (layer "B.SilkS")
      (effects (font (size 0.7 0.7) (thickness 0.15)) (justify left bottom mirror))
    )
    (fp_text value "C_100n_0402" (at 0 -1.4 90) (layer "B.Fab")
      (effects (font (size 0.7 0.7) (thickness 0.15)) (justify left bottom mirror))
    )
    (fp_text user "Author: Antmicro" (at -0.932 -4.17 90) (layer "B.Fab") hide
      (effects (font (size 0.7 0.7) (thickness 0.15)) (justify left bottom mirror))
    )
    (fp_text user "${REFERENCE}" (at -0.932 -3.168 90) (layer "B.Fab") hide
      (effects (font (size 0.7 0.7) (thickness 0.15)) (justify left bottom mirror))
    )
    (fp_text user "License: Apache-2.0" (at -0.932 -5.17 90) (layer "B.Fab") hide
      (effects (font (size 0.7 0.7) (thickness 0.15)) (justify left bottom mirror))
    )
    (fp_rect (start -0.94 0.47) (end 0.94 -0.47) (layer "B.CrtYd") (width 0.05) (fill none))
    (fp_rect (start -0.499 0.249) (end 0.499 -0.249) (layer "B.Fab") (width 0.15) (fill none))
    (pad "1" smd roundrect (at -0.484 0 270) (size 0.59 0.64) (layers "B.Cu" "B.Paste" "B.Mask") (roundrect_rratio 0.25)
      (net 64 "USB1_SS_TX0_P") (pintype "passive"))
    (pad "2" smd roundrect (at 0.484 0 270) (size 0.59 0.64) (layers "B.Cu" "B.Paste" "B.Mask") (roundrect_rratio 0.25)
      (net 302 "/USB-C Interface /USB1C_TX0_C_P") (pintype "passive"))
  )
	(footprint "sa800u-baseboard-hw-footprints:C_0402_1005Metric" (layer "B.Cu")
    (tedit 616D63CF)
    (at 98.5 138.1 90)
    (descr "Capacitor SMD 0402")
    (tags "capacitor SMD 0402")
    (property "Author" "Antmicro")
    (property "Dielectric" "X5R")
    (property "License" "Apache-2.0")
    (property "MPN" "GRM155R61H104KE14D")
    (property "Manufacturer" "Murata")
    (property "Sheetfile" "usb-c-interface.kicad_sch")
    (property "Sheetname" "USB-C Interface ")
    (property "Val" "100n")
    (property "Voltage" "50V")
    (attr smd)
    (fp_text reference "C87" (at 3.07 0.36 270) (layer "B.SilkS")
      (effects (font (size 0.7 0.7) (thickness 0.15)) (justify left bottom mirror))
    )
    (fp_text value "C_100n_0402" (at 0 -1.4 270) (layer "B.Fab")
      (effects (font (size 0.7 0.7) (thickness 0.15)) (justify left bottom mirror))
    )
    (fp_text user "License: Apache-2.0" (at -0.932 -5.17 270) (layer "B.Fab") hide
      (effects (font (size 0.7 0.7) (thickness 0.15)) (justify left bottom mirror))
    )
    (fp_text user "Author: Antmicro" (at -0.932 -4.17 270) (layer "B.Fab") hide
      (effects (font (size 0.7 0.7) (thickness 0.15)) (justify left bottom mirror))
    )
    (fp_text user "${REFERENCE}" (at -0.932 -3.168 270) (layer "B.Fab") hide
      (effects (font (size 0.7 0.7) (thickness 0.15)) (justify left bottom mirror))
    )
    (fp_rect (start -0.94 0.47) (end 0.94 -0.47) (layer "B.CrtYd") (width 0.05) (fill none))
    (fp_rect (start -0.499 0.249) (end 0.499 -0.249) (layer "B.Fab") (width 0.15) (fill none))
    (pad "1" smd roundrect (at -0.484 0 90) (size 0.59 0.64) (layers "B.Cu" "B.Paste" "B.Mask") (roundrect_rratio 0.25)
      (net 323 "/USB-C Interface /USB1C_RX0_C_N") (pintype "passive"))
    (pad "2" smd roundrect (at 0.484 0 90) (size 0.59 0.64) (layers "B.Cu" "B.Paste" "B.Mask") (roundrect_rratio 0.25)
      (net 70 "USB1_SS_RX0_N") (pintype "passive"))
  )
	(footprint "sa800u-baseboard-hw-footprints:C_0402_1005Metric" (layer "B.Cu")
    (tedit 616D63CF)
    (at 100.5 138.1 -90)
    (descr "Capacitor SMD 0402")
    (tags "capacitor SMD 0402")
    (property "Author" "Antmicro")
    (property "Dielectric" "X5R")
    (property "License" "Apache-2.0")
    (property "MPN" "GRM155R61H104KE14D")
    (property "Manufacturer" "Murata")
    (property "Sheetfile" "usb-c-interface.kicad_sch")
    (property "Sheetname" "USB-C Interface ")
    (property "Val" "100n")
    (property "Voltage" "50V")
    (attr smd)
    (fp_text reference "C79" (at -3.098 -0.31 90) (layer "B.SilkS")
      (effects (font (size 0.7 0.7) (thickness 0.15)) (justify left bottom mirror))
    )
    (fp_text value "C_100n_0402" (at 0 -1.4 90) (layer "B.Fab")
      (effects (font (size 0.7 0.7) (thickness 0.15)) (justify left bottom mirror))
    )
    (fp_text user "License: Apache-2.0" (at -0.932 -5.17 90) (layer "B.Fab") hide
      (effects (font (size 0.7 0.7) (thickness 0.15)) (justify left bottom mirror))
    )
    (fp_text user "${REFERENCE}" (at -0.932 -3.168 90) (layer "B.Fab") hide
      (effects (font (size 0.7 0.7) (thickness 0.15)) (justify left bottom mirror))
    )
    (fp_text user "Author: Antmicro" (at -0.932 -4.17 90) (layer "B.Fab") hide
      (effects (font (size 0.7 0.7) (thickness 0.15)) (justify left bottom mirror))
    )
    (fp_rect (start -0.94 0.47) (end 0.94 -0.47) (layer "B.CrtYd") (width 0.05) (fill none))
    (fp_rect (start -0.499 0.249) (end 0.499 -0.249) (layer "B.Fab") (width 0.15) (fill none))
    (pad "1" smd roundrect (at -0.484 0 270) (size 0.59 0.64) (layers "B.Cu" "B.Paste" "B.Mask") (roundrect_rratio 0.25)
      (net 65 "USB1_SS_TX0_N") (pintype "passive"))
    (pad "2" smd roundrect (at 0.484 0 270) (size 0.59 0.64) (layers "B.Cu" "B.Paste" "B.Mask") (roundrect_rratio 0.25)
      (net 303 "/USB-C Interface /USB1C_TX0_C_N") (pintype "passive"))
  )
)
